(kicad_pcb
	(version 20260206)
	(generator "pcbnew")
	(generator_version "10.0")
	(general
		(thickness 1.6)
		(legacy_teardrops no)
	)
	(paper "A4")
	(title_block
		(title "netronome-mezz — pcbd0082-001_rev01_jul9_a.brd")
		(comment 1 "Open CloudServer (Microsoft) / footprints 399-409 of 714")
	)
	(layers
		(0 "F.Cu" signal "TOP")
		(4 "In1.Cu" signal "02_GND")
		(6 "In2.Cu" signal "03_SIG")
		(8 "In3.Cu" signal "04_SIG")
		(10 "In4.Cu" signal "05_GND")
		(12 "In5.Cu" signal "06_PWR1")
		(14 "In6.Cu" signal "07_SIG")
		(16 "In7.Cu" signal "08_SIG")
		(18 "In8.Cu" signal "09_GND")
		(2 "B.Cu" signal "BOTTOM")
		(9 "F.Adhes" user "F.Adhesive")
		(11 "B.Adhes" user "B.Adhesive")
		(13 "F.Paste" user "Package Geometry/Pastemask Top")
		(15 "B.Paste" user "Package Geometry/Pastemask Bottom")
		(5 "F.SilkS" user "Ref Des/Silkscreen Top")
		(7 "B.SilkS" user "Ref Des/Silkscreen Bottom")
		(1 "F.Mask" user "Board Geometry/Soldermask Top")
		(3 "B.Mask" user "Board Geometry/Soldermask Bottom")
		(17 "Dwgs.User" user "User.Drawings")
		(19 "Cmts.User" user "User.Comments")
		(21 "Eco1.User" user "User.Eco1")
		(23 "Eco2.User" user "User.Eco2")
		(25 "Edge.Cuts" user "Board Geometry/Outline")
		(27 "Margin" user)
		(31 "F.CrtYd" user "Package Geometry/Place Bound Top")
		(29 "B.CrtYd" user "Package Geometry/Place Bound Bottom")
		(35 "F.Fab" user "Ref Des/Assembly Top")
		(33 "B.Fab" user "Ref Des/Assembly Bottom")
		(45 "User.4" user "COMPVAL_TYPE_BOTTOM")
	)
	(footprint ""
		(layer "B.Cu")
		(at 31.1912 27.686 -90)
		(property "Reference" "C122"
			(at 0.40767 0.9652 0)
			(unlocked yes)
			(layer "B.SilkS")
			(effects
				(font
					(size 0.7874 0.5842)
					(thickness 0.127)
				)
				(justify left mirror)
			)
		)
		(property "Value" "0.1UF"
			(at 0.091846 0.2921 180)
			(unlocked yes)
			(layer "B.Fab")
			(hide yes)
			(effects
				(font
					(size 0.7874 0.5842)
					(thickness 0.2032)
				)
				(justify left mirror)
			)
		)
		(property "Device Type" "CAPC0073"
			(at 0.091846 0.2921 180)
			(unlocked yes)
			(layer "B.Fab")
			(hide yes)
			(effects
				(font
					(size 0.7874 0.5842)
					(thickness 0.2032)
				)
				(justify left mirror)
			)
		)
		(duplicate_pad_numbers_are_jumpers no)
		(fp_poly
			(pts
				(xy -0.635 1.0668) (xy -0.635 -1.0668) (xy 0.635 -1.0668) (xy 0.635 1.0668)
			)
			(stroke
				(width 0)
				(type default)
			)
			(fill no)
			(layer "B.CrtYd")
		)
		(fp_line
			(start -0.254 0.508)
			(end 0.254 0.508)
			(stroke
				(width 0.0254)
				(type default)
			)
			(layer "B.Fab")
		)
		(fp_line
			(start 0.254 0.508)
			(end 0.254 -0.508)
			(stroke
				(width 0.0254)
				(type default)
			)
			(layer "B.Fab")
		)
		(fp_line
			(start -0.254 -0.508)
			(end -0.254 0.508)
			(stroke
				(width 0.0254)
				(type default)
			)
			(layer "B.Fab")
		)
		(fp_line
			(start 0.254 -0.508)
			(end -0.254 -0.508)
			(stroke
				(width 0.0254)
				(type default)
			)
			(layer "B.Fab")
		)
		(pad "1" smd rect
			(at 0 -0.4191 90)
			(size 0.508 0.5334)
			(layers "B.Cu" "B.Mask" "B.Paste")
			(net "EXT_3.3V")
		)
		(pad "2" smd rect
			(at 0 0.4191 90)
			(size 0.508 0.5334)
			(layers "B.Cu" "B.Mask" "B.Paste")
			(net "GND")
		)
		(zone
			(layer "B.Cu")
			(hatch none 0.5)
			(connect_pads
				(clearance 0)
			)
			(min_thickness 0.25)
			(keepout
				(tracks not_allowed)
				(vias allowed)
				(pads allowed)
				(copperpour not_allowed)
				(footprints allowed)
			)
			(placement
				(enabled no)
				(sheetname "")
			)
			(fill
				(thermal_gap 0.5)
				(thermal_bridge_width 0.5)
				(island_removal_mode 0)
			)
			(polygon
				(pts
					(xy 31.2166 27.6606) (xy 31.1658 27.6606) (xy 31.1658 27.7114) (xy 31.2166 27.7114)
				)
			)
		)
	)
	(footprint ""
		(layer "B.Cu")
		(at 54.483 0.762 180)
		(property "Reference" "C145"
			(at 0.145212 0.8763 270)
			(unlocked yes)
			(layer "B.SilkS")
			(effects
				(font
					(size 0.7874 0.5842)
					(thickness 0.127)
				)
				(justify left mirror)
			)
		)
		(property "Value" "0.22UF"
			(at 0.091846 0.2921 90)
			(unlocked yes)
			(layer "B.Fab")
			(hide yes)
			(effects
				(font
					(size 0.7874 0.5842)
					(thickness 0.2032)
				)
				(justify left mirror)
			)
		)
		(property "Device Type" "CAPC0062"
			(at 0.091846 0.2921 90)
			(unlocked yes)
			(layer "B.Fab")
			(hide yes)
			(effects
				(font
					(size 0.7874 0.5842)
					(thickness 0.2032)
				)
				(justify left mirror)
			)
		)
		(duplicate_pad_numbers_are_jumpers no)
		(fp_poly
			(pts
				(xy -0.635 1.0668) (xy -0.635 -1.0668) (xy 0.635 -1.0668) (xy 0.635 1.0668)
			)
			(stroke
				(width 0)
				(type default)
			)
			(fill no)
			(layer "B.CrtYd")
		)
		(fp_line
			(start 0.254 0.508)
			(end 0.254 -0.508)
			(stroke
				(width 0.0254)
				(type default)
			)
			(layer "B.Fab")
		)
		(fp_line
			(start 0.254 -0.508)
			(end -0.254 -0.508)
			(stroke
				(width 0.0254)
				(type default)
			)
			(layer "B.Fab")
		)
		(fp_line
			(start -0.254 0.508)
			(end 0.254 0.508)
			(stroke
				(width 0.0254)
				(type default)
			)
			(layer "B.Fab")
		)
		(fp_line
			(start -0.254 -0.508)
			(end -0.254 0.508)
			(stroke
				(width 0.0254)
				(type default)
			)
			(layer "B.Fab")
		)
		(pad "1" smd rect
			(at 0 -0.4191)
			(size 0.508 0.5334)
			(layers "B.Cu" "B.Mask" "B.Paste")
			(net "_NFP_PCIE0_PER4_P")
		)
		(pad "2" smd rect
			(at 0 0.4191)
			(size 0.508 0.5334)
			(layers "B.Cu" "B.Mask" "B.Paste")
			(net "NFP_PCIE0_PER4_P")
		)
		(zone
			(layer "B.Cu")
			(hatch none 0.5)
			(connect_pads
				(clearance 0)
			)
			(min_thickness 0.25)
			(keepout
				(tracks not_allowed)
				(vias allowed)
				(pads allowed)
				(copperpour not_allowed)
				(footprints allowed)
			)
			(placement
				(enabled no)
				(sheetname "")
			)
			(fill
				(thermal_gap 0.5)
				(thermal_bridge_width 0.5)
				(island_removal_mode 0)
			)
			(polygon
				(pts
					(xy 54.5084 0.7874) (xy 54.5084 0.7366) (xy 54.4576 0.7366) (xy 54.4576 0.7874)
				)
			)
		)
	)
	(footprint ""
		(layer "B.Cu")
		(at 33.655 32.639)
		(property "Reference" "R177"
			(at -0.02667 4.318 270)
			(unlocked yes)
			(layer "B.SilkS")
			(effects
				(font
					(size 0.7874 0.5842)
					(thickness 0.127)
				)
				(justify left mirror)
			)
		)
		(property "Value" "0"
			(at 0.148158 1.3462 270)
			(unlocked yes)
			(layer "B.Fab")
			(hide yes)
			(effects
				(font
					(size 1.27 0.9652)
					(thickness 0.000001)
				)
				(justify left mirror)
			)
		)
		(property "Device Type" "REST1111"
			(at 0.148158 1.3462 270)
			(unlocked yes)
			(layer "B.Fab")
			(hide yes)
			(effects
				(font
					(size 1.27 0.9652)
					(thickness 0.000001)
				)
				(justify left mirror)
			)
		)
		(duplicate_pad_numbers_are_jumpers no)
		(fp_poly
			(pts
				(xy -0.635 1.0668) (xy -0.635 -1.0668) (xy 0.635 -1.0668) (xy 0.635 1.0668)
			)
			(stroke
				(width 0)
				(type default)
			)
			(fill no)
			(layer "B.CrtYd")
		)
		(fp_line
			(start -0.254 -0.508)
			(end -0.254 0.508)
			(stroke
				(width 0.0254)
				(type default)
			)
			(layer "B.Fab")
		)
		(fp_line
			(start -0.254 0.508)
			(end 0.254 0.508)
			(stroke
				(width 0.0254)
				(type default)
			)
			(layer "B.Fab")
		)
		(fp_line
			(start 0.254 -0.508)
			(end -0.254 -0.508)
			(stroke
				(width 0.0254)
				(type default)
			)
			(layer "B.Fab")
		)
		(fp_line
			(start 0.254 0.508)
			(end 0.254 -0.508)
			(stroke
				(width 0.0254)
				(type default)
			)
			(layer "B.Fab")
		)
		(pad "1" smd rect
			(at 0 -0.4191 180)
			(size 0.508 0.5334)
			(layers "B.Cu" "B.Mask" "B.Paste")
			(net "NFP_CORE_VID5")
		)
		(pad "2" smd rect
			(at 0 0.4191 180)
			(size 0.508 0.5334)
			(layers "B.Cu" "B.Mask" "B.Paste")
			(net "_NFP_CORE_VID5")
		)
		(zone
			(layer "B.Cu")
			(hatch none 0.5)
			(connect_pads
				(clearance 0)
			)
			(min_thickness 0.25)
			(keepout
				(tracks not_allowed)
				(vias allowed)
				(pads allowed)
				(copperpour not_allowed)
				(footprints allowed)
			)
			(placement
				(enabled no)
				(sheetname "")
			)
			(fill
				(thermal_gap 0.5)
				(thermal_bridge_width 0.5)
				(island_removal_mode 0)
			)
			(polygon
				(pts
					(xy 33.6296 32.6136) (xy 33.6296 32.6644) (xy 33.6804 32.6644) (xy 33.6804 32.6136)
				)
			)
		)
	)
	(footprint ""
		(layer "B.Cu")
		(at 54.737 21.072094 -90)
		(property "Reference" "L7"
			(at -1.006094 -0.10033 270)
			(unlocked yes)
			(layer "B.SilkS")
			(effects
				(font
					(size 0.7874 0.5842)
					(thickness 0.127)
				)
				(justify left mirror)
			)
		)
		(property "Value" ""
			(at 0 0 90)
			(layer "B.Fab")
			(effects
				(font
					(size 1.27 1.27)
				)
				(justify mirror)
			)
		)
		(duplicate_pad_numbers_are_jumpers no)
		(fp_line
			(start -0.0254 0.127)
			(end 0.0254 0.127)
			(stroke
				(width 0.1016)
				(type default)
			)
			(layer "B.SilkS")
		)
		(fp_line
			(start 0.0254 0.127)
			(end 0.0254 -0.127)
			(stroke
				(width 0.1016)
				(type default)
			)
			(layer "B.SilkS")
		)
		(fp_line
			(start -0.0254 -0.127)
			(end -0.0254 0.127)
			(stroke
				(width 0.1016)
				(type default)
			)
			(layer "B.SilkS")
		)
		(fp_line
			(start 0.0254 -0.127)
			(end -0.0254 -0.127)
			(stroke
				(width 0.1016)
				(type default)
			)
			(layer "B.SilkS")
		)
		(fp_poly
			(pts
				(xy -0.889 -0.4953) (xy -0.889 0.4953) (xy 0.889 0.4953) (xy 0.889 -0.4953)
			)
			(stroke
				(width 0)
				(type default)
			)
			(fill no)
			(layer "B.CrtYd")
		)
		(fp_line
			(start -0.508 0.254)
			(end -0.508 -0.254)
			(stroke
				(width 0.0254)
				(type default)
			)
			(layer "B.Fab")
		)
		(fp_line
			(start 0.508 0.254)
			(end -0.508 0.254)
			(stroke
				(width 0.0254)
				(type default)
			)
			(layer "B.Fab")
		)
		(fp_line
			(start -0.508 -0.254)
			(end 0.508 -0.254)
			(stroke
				(width 0.0254)
				(type default)
			)
			(layer "B.Fab")
		)
		(fp_line
			(start 0.508 -0.254)
			(end 0.508 0.254)
			(stroke
				(width 0.0254)
				(type default)
			)
			(layer "B.Fab")
		)
		(pad "1" smd rect
			(at 0.4699 0 90)
			(size 0.5334 0.508)
			(layers "B.Cu" "B.Mask" "B.Paste")
			(net "DDR_1.8V")
		)
		(pad "2" smd rect
			(at -0.4699 0 90)
			(size 0.5334 0.508)
			(layers "B.Cu" "B.Mask" "B.Paste")
			(net "VDDA_DDR0_32A")
		)
	)
	(footprint ""
		(layer "B.Cu")
		(at 81.850992 19.055994)
		(property "Reference" "V2_A-BA1"
			(at 0 0 0)
			(layer "B.SilkS")
			(hide yes)
			(effects
				(font
					(size 1.27 1.27)
				)
				(justify mirror)
			)
		)
		(property "Value" ""
			(at 0 0 0)
			(layer "B.Fab")
			(effects
				(font
					(size 1.27 1.27)
				)
				(justify mirror)
			)
		)
		(duplicate_pad_numbers_are_jumpers no)
		(pad "1" thru_hole circle
			(at 0 0 180)
			(size 0.4572 0.4572)
			(drill 0.20574)
			(layers "*.Cu" "*.Mask")
			(remove_unused_layers no)
			(net "DDR0_32A_BA1")
			(clearance 0.1143)
			(thermal_gap 0.1143)
		)
	)
	(footprint ""
		(layer "B.Cu")
		(at 73.851008 2.699004)
		(property "Reference" "V_A-DM1"
			(at 0 0 0)
			(layer "B.SilkS")
			(hide yes)
			(effects
				(font
					(size 1.27 1.27)
				)
				(justify mirror)
			)
		)
		(property "Value" ""
			(at 0 0 0)
			(layer "B.Fab")
			(effects
				(font
					(size 1.27 1.27)
				)
				(justify mirror)
			)
		)
		(duplicate_pad_numbers_are_jumpers no)
		(pad "1" thru_hole circle
			(at 0 0 180)
			(size 0.4572 0.4572)
			(drill 0.20574)
			(layers "*.Cu" "*.Mask")
			(remove_unused_layers no)
			(net "DDR0_32A_DM1")
			(clearance 0.1143)
			(thermal_gap 0.1143)
		)
	)
	(footprint ""
		(layer "B.Cu")
		(at 33.401 28.321 180)
		(property "Reference" "R159"
			(at 0 0 0)
			(layer "B.SilkS")
			(hide yes)
			(effects
				(font
					(size 1.27 1.27)
				)
				(justify mirror)
			)
		)
		(property "Value" "0"
			(at 0.148158 1.3462 90)
			(unlocked yes)
			(layer "B.Fab")
			(hide yes)
			(effects
				(font
					(size 1.27 0.9652)
					(thickness 0.000001)
				)
				(justify left mirror)
			)
		)
		(property "Device Type" "REST1111"
			(at 0.148158 1.3462 90)
			(unlocked yes)
			(layer "B.Fab")
			(hide yes)
			(effects
				(font
					(size 1.27 0.9652)
					(thickness 0.000001)
				)
				(justify left mirror)
			)
		)
		(duplicate_pad_numbers_are_jumpers no)
		(fp_poly
			(pts
				(xy -0.635 1.0668) (xy -0.635 -1.0668) (xy 0.635 -1.0668) (xy 0.635 1.0668)
			)
			(stroke
				(width 0)
				(type default)
			)
			(fill no)
			(layer "B.CrtYd")
		)
		(fp_line
			(start 0.254 0.508)
			(end 0.254 -0.508)
			(stroke
				(width 0.0254)
				(type default)
			)
			(layer "B.Fab")
		)
		(fp_line
			(start 0.254 -0.508)
			(end -0.254 -0.508)
			(stroke
				(width 0.0254)
				(type default)
			)
			(layer "B.Fab")
		)
		(fp_line
			(start -0.254 0.508)
			(end 0.254 0.508)
			(stroke
				(width 0.0254)
				(type default)
			)
			(layer "B.Fab")
		)
		(fp_line
			(start -0.254 -0.508)
			(end -0.254 0.508)
			(stroke
				(width 0.0254)
				(type default)
			)
			(layer "B.Fab")
		)
		(pad "1" smd rect
			(at 0 -0.4191)
			(size 0.508 0.5334)
			(layers "B.Cu" "B.Mask" "B.Paste")
			(net "CPLD_PGRM_JTAG_TDI")
		)
		(pad "2" smd rect
			(at 0 0.4191)
			(size 0.508 0.5334)
			(layers "B.Cu" "B.Mask" "B.Paste")
			(net "CPLD_PGRM_JTAG_TDO")
		)
		(zone
			(layer "B.Cu")
			(hatch none 0.5)
			(connect_pads
				(clearance 0)
			)
			(min_thickness 0.25)
			(keepout
				(tracks not_allowed)
				(vias allowed)
				(pads allowed)
				(copperpour not_allowed)
				(footprints allowed)
			)
			(placement
				(enabled no)
				(sheetname "")
			)
			(fill
				(thermal_gap 0.5)
				(thermal_bridge_width 0.5)
				(island_removal_mode 0)
			)
			(polygon
				(pts
					(xy 33.4264 28.3464) (xy 33.4264 28.2956) (xy 33.3756 28.2956) (xy 33.3756 28.3464)
				)
			)
		)
	)
	(footprint ""
		(layer "B.Cu")
		(at 72.251011 15.056002)
		(property "Reference" "V_A-DQ29"
			(at 0 0 0)
			(layer "B.SilkS")
			(hide yes)
			(effects
				(font
					(size 1.27 1.27)
				)
				(justify mirror)
			)
		)
		(property "Value" ""
			(at 0 0 0)
			(layer "B.Fab")
			(effects
				(font
					(size 1.27 1.27)
				)
				(justify mirror)
			)
		)
		(duplicate_pad_numbers_are_jumpers no)
		(pad "1" thru_hole circle
			(at 0 0 180)
			(size 0.4572 0.4572)
			(drill 0.20574)
			(layers "*.Cu" "*.Mask")
			(remove_unused_layers no)
			(net "DDR0_32A_DQ29")
			(clearance 0.1143)
			(thermal_gap 0.1143)
		)
	)
	(footprint ""
		(layer "B.Cu")
		(at 73.851008 3.499002)
		(property "Reference" "V_A-DQ09"
			(at 0 0 0)
			(layer "B.SilkS")
			(hide yes)
			(effects
				(font
					(size 1.27 1.27)
				)
				(justify mirror)
			)
		)
		(property "Value" ""
			(at 0 0 0)
			(layer "B.Fab")
			(effects
				(font
					(size 1.27 1.27)
				)
				(justify mirror)
			)
		)
		(duplicate_pad_numbers_are_jumpers no)
		(pad "1" thru_hole circle
			(at 0 0 180)
			(size 0.4572 0.4572)
			(drill 0.20574)
			(layers "*.Cu" "*.Mask")
			(remove_unused_layers no)
			(net "DDR0_32A_DQ9")
			(clearance 0.1143)
			(thermal_gap 0.1143)
		)
	)
	(footprint ""
		(layer "B.Cu")
		(at 38.608 39.751)
		(property "Reference" "TP33"
			(at 1.524 1.55067 0)
			(unlocked yes)
			(layer "B.SilkS")
			(effects
				(font
					(size 0.7874 0.5842)
					(thickness 0.127)
				)
				(justify left mirror)
			)
		)
		(property "Value" "*"
			(at 0.4826 -0.14732 0)
			(unlocked yes)
			(layer "B.Fab")
			(hide yes)
			(effects
				(font
					(size 1.27 0.9652)
					(thickness 0.000001)
				)
				(justify left mirror)
			)
		)
		(property "Device Type" "TP_SMALL"
			(at 0.4826 -0.14732 0)
			(unlocked yes)
			(layer "B.Fab")
			(hide yes)
			(effects
				(font
					(size 1.27 0.9652)
					(thickness 0.000001)
				)
				(justify left mirror)
			)
		)
		(duplicate_pad_numbers_are_jumpers no)
		(fp_line
			(start -0.8636 -0.8636)
			(end 0.8636 -0.8636)
			(stroke
				(width 0.1524)
				(type default)
			)
			(layer "B.SilkS")
		)
		(fp_line
			(start -0.8636 0.8636)
			(end -0.8636 -0.8636)
			(stroke
				(width 0.1524)
				(type default)
			)
			(layer "B.SilkS")
		)
		(fp_line
			(start 0.8636 -0.8636)
			(end 0.8636 0.8636)
			(stroke
				(width 0.1524)
				(type default)
			)
			(layer "B.SilkS")
		)
		(fp_line
			(start 0.8636 0.8636)
			(end -0.8636 0.8636)
			(stroke
				(width 0.1524)
				(type default)
			)
			(layer "B.SilkS")
		)
		(fp_poly
			(pts
				(xy 0.635 -0.635) (xy 0.635 0.635) (xy -0.635 0.635) (xy -0.635 -0.635)
			)
			(stroke
				(width 0)
				(type default)
			)
			(fill no)
			(layer "B.CrtYd")
		)
		(pad "1" smd rect
			(at 0 0 180)
			(size 1.27 1.27)
			(layers "B.Cu" "B.Mask" "B.Paste")
			(net "GH_PHASE2")
		)
	)
	(footprint ""
		(layer "B.Cu")
		(at 39.237031 11.542014)
		(property "Reference" "R42"
			(at -0.909701 -0.493014 270)
			(unlocked yes)
			(layer "B.SilkS")
			(effects
				(font
					(size 0.7874 0.5842)
					(thickness 0.127)
				)
				(justify mirror)
			)
		)
		(property "Value" ""
			(at 0 0 0)
			(layer "B.Fab")
			(effects
				(font
					(size 1.27 1.27)
				)
				(justify mirror)
			)
		)
		(duplicate_pad_numbers_are_jumpers no)
		(fp_circle
			(center 0 0)
			(end 0.104648 0)
			(stroke
				(width 0.1016)
				(type default)
			)
			(fill no)
			(layer "B.SilkS")
		)
		(fp_poly
			(pts
				(xy 0.381 -0.889) (xy 0.381 0.889) (xy -0.381 0.889) (xy -0.381 -0.889)
			)
			(stroke
				(width 0)
				(type default)
			)
			(fill no)
			(layer "B.CrtYd")
		)
		(fp_line
			(start -0.508 -1.016)
			(end -0.508 1.016)
			(stroke
				(width 0.0254)
				(type default)
			)
			(layer "B.Fab")
		)
		(fp_line
			(start -0.508 1.016)
			(end 0.508 1.016)
			(stroke
				(width 0.0254)
				(type default)
			)
			(layer "B.Fab")
		)
		(fp_line
			(start 0.254 -1.016)
			(end -0.508 -1.016)
			(stroke
				(width 0.0254)
				(type default)
			)
			(layer "B.Fab")
		)
		(fp_line
			(start 0.508 -1.016)
			(end 0.254 -1.016)
			(stroke
				(width 0.0254)
				(type default)
			)
			(layer "B.Fab")
		)
		(fp_line
			(start 0.508 1.016)
			(end 0.508 -1.016)
			(stroke
				(width 0.0254)
				(type default)
			)
			(layer "B.Fab")
		)
		(pad "1" smd custom
			(at 0 -0.500126 180)
			(size 0.127 0.127)
			(layers "B.Cu" "B.Mask" "B.Paste")
			(net "VDD_3.3V")
			(options
				(clearance outline)
				(anchor circle)
			)
			(primitives
				(gr_poly
					(pts
						(xy -0.1778 0.254) (xy 0.1778 0.254) (xy 0.254 0.1778) (xy 0.254 -0.1778) (xy 0.1778 -0.254) (xy -0.1778 -0.254)
						(xy -0.254 -0.1778) (xy -0.254 0.1778)
					)
					(width 0)
					(fill yes)
				)
			)
		)
		(pad "2" smd custom
			(at 0 0.500126 180)
			(size 0.127 0.127)
			(layers "B.Cu" "B.Mask" "B.Paste")
			(net "PGRM_JTAG_TMS")
			(options
				(clearance outline)
				(anchor circle)
			)
			(primitives
				(gr_poly
					(pts
						(xy -0.1778 0.254) (xy 0.1778 0.254) (xy 0.254 0.1778) (xy 0.254 -0.1778) (xy 0.1778 -0.254) (xy -0.1778 -0.254)
						(xy -0.254 -0.1778) (xy -0.254 0.1778)
					)
					(width 0)
					(fill yes)
				)
			)
		)
	)
)
